# Barreleye-G2_Tri-mode Expander-DVT-X01-SKU-BOM-X07-20171222_Final.xls.xlsx — DEPOP_GA (bom)
| FOXCONN TECHNOLOGY GROUP |  |  |  |  |  |  |  |  |  |  |  |  |
| BILL OF MATERIAL |  |  |  |  |  |  |  |  |  |  |  |  |
| REV OF  BOM |  | CUSTOMER | <name> |  | CUSTOMER P/N |  | PRODUCT CODE |  | PWA  REV |  | DATE |  |
| Sourcing (Single/Sole/Multi) | Critical Commodity (Y or N) | Component Class (1, 2, other) | Customer PSL (Y or N) | Item Number | Foxconn P/N | Customer P/N | Part Description | Manufacturer  Full Name | Manufacturer  Part Number | Qty | RoHS Status | Location |
